# TIMECARD (Time Appliance Project (Time Card)) — schematic netlist excerpt (pin names and nets, part order shuffled) for the footprints in the layout excerpt that follows; sources: Cadence DE-HDL packaged netlist, KiCad conversion of R4006-B0001-02_R01.brd

U31  CAT93C46VI_GT3_SOIC8  pkg SOP8_154_P050_V1  page 24
  CS  = FTDI_EE_CS
  SK  = FTDI_EE_CLK
  DI  = FTDI_EE_DAT
  DO  = FTDI_EE_DO
  GND  = SG
  ORG  = XP3R3V_FT4232
  NC  = NC
  VCC  = XP3R3V_FT4232

(kicad_pcb
	(version 20260206)
	(generator "pcbnew")
	(generator_version "10.0")
	(general
		(thickness 1.6)
		(legacy_teardrops no)
	)
	(paper "A4")
	(title_block
		(title "timecard-production-celestica-r4006 — R4006-B0001-02_R01.brd")
		(comment 1 "Time Appliance Project (Time Card) / footprint 879 of 1113 (U31), pads 1-8 of 8")
	)
	(layers
		(0 "F.Cu" signal "TOP")
		(4 "In1.Cu" signal "L02_GND1")
		(6 "In2.Cu" signal "L03_SIG1")
		(8 "In3.Cu" signal "L04_GND2")
		(10 "In4.Cu" signal "L05_VCC1")
		(12 "In5.Cu" signal "L06_VCC2")
		(14 "In6.Cu" signal "L07_GND3")
		(16 "In7.Cu" signal "L08_SIG2")
		(18 "In8.Cu" signal "L09_GND4")
		(2 "B.Cu" signal "BOTTOM")
		(9 "F.Adhes" user "F.Adhesive")
		(11 "B.Adhes" user "B.Adhesive")
		(13 "F.Paste" user "Package Geometry/Pastemask Top")
		(15 "B.Paste" user "Package Geometry/Pastemask Bottom")
		(5 "F.SilkS" user "Ref Des/Silkscreen Top")
		(7 "B.SilkS" user "Ref Des/Silkscreen Bottom")
		(1 "F.Mask" user "Board Geometry/Soldermask Top")
		(3 "B.Mask" user "Board Geometry/Soldermask Bottom")
		(17 "Dwgs.User" user "User.Drawings")
		(19 "Cmts.User" user "User.Comments")
		(21 "Eco1.User" user "User.Eco1")
		(23 "Eco2.User" user "User.Eco2")
		(25 "Edge.Cuts" user "Board Geometry/Outline")
		(27 "Margin" user)
		(31 "F.CrtYd" user "Package Geometry/Place Bound Top")
		(29 "B.CrtYd" user "Package Geometry/Place Bound Bottom")
		(35 "F.Fab" user "Ref Des/Assembly Top")
		(33 "B.Fab" user "Ref Des/Assembly Bottom")
	)
	(footprint ""
		(layer "B.Cu")
		(at 47.2186 -87.9602)
		(property "Reference" "U31"
			(at 0.2794 -3.69443 0)
			(unlocked yes)
			(layer "B.SilkS")
			(effects
				(font
					(size 0.7874 0.5842)
					(thickness 0.1524)
				)
				(justify mirror)
			)
		)
		(property "Value" ""
			(at 0 0 0)
			(layer "B.Fab")
			(effects
				(font
					(size 1.27 1.27)
				)
				(justify mirror)
			)
		)
		(property "User Part Number" "PARTNUM*"
			(at 0.0508 4.52247 0)
			(unlocked yes)
			(layer "Cmts.User")
			(hide yes)
			(effects
				(font
					(size 0.7874 0.5842)
					(thickness 0.1524)
				)
				(justify mirror)
			)
		)
		(property "Device Type" "CAT93C46VI_GT3_SOIC8-G221-1007A"
			(at 0.0254 3.50647 0)
			(unlocked yes)
			(layer "B.Fab")
			(hide yes)
			(effects
				(font
					(size 0.7874 0.5842)
					(thickness 0.1524)
				)
				(justify mirror)
			)
		)
		(duplicate_pad_numbers_are_jumpers no)
		(pad "1" smd rect
			(at 2.8067 -1.905 90)
			(size 0.508 1.651)
			(layers "B.Cu" "B.Mask" "B.Paste")
			(net "FTDI_EE_CS")
		)
		(pad "2" smd rect
			(at 2.8067 -0.635 90)
			(size 0.508 1.651)
			(layers "B.Cu" "B.Mask" "B.Paste")
			(net "FTDI_EE_CLK")
		)
		(pad "3" smd rect
			(at 2.8067 0.635 90)
			(size 0.508 1.651)
			(layers "B.Cu" "B.Mask" "B.Paste")
			(net "FTDI_EE_DAT")
		)
		(pad "4" smd rect
			(at 2.8067 1.905 90)
			(size 0.508 1.651)
			(layers "B.Cu" "B.Mask" "B.Paste")
			(net "FTDI_EE_DO")
		)
		(pad "5" smd rect
			(at -2.8067 1.905 90)
			(size 0.508 1.651)
			(layers "B.Cu" "B.Mask" "B.Paste")
			(net "SG")
		)
		(pad "6" smd rect
			(at -2.8067 0.635 90)
			(size 0.508 1.651)
			(layers "B.Cu" "B.Mask" "B.Paste")
			(net "XP3R3V_FT4232")
		)
		(pad "7" smd rect
			(at -2.8067 -0.635 90)
			(size 0.508 1.651)
			(layers "B.Cu" "B.Mask" "B.Paste")
			(net "Net_296")
		)
		(pad "8" smd rect
			(at -2.8067 -1.905 90)
			(size 0.508 1.651)
			(layers "B.Cu" "B.Mask" "B.Paste")
			(net "XP3R3V_FT4232")
		)
	)
)
